# T6G (Grand Teton) — schematic netlist excerpt (pin names and nets, part order shuffled) for the footprints in the layout excerpt that follows; sources: Cadence DE-HDL packaged netlist, KiCad conversion of 04192023_DAF0TMB3IC0_F0TG_MB_C_brd_V02_OCP.brd

C368  Q_CAP  22UF 4V 20% X6S  pkg C0402  page 345 : A = P1V8_CPU1_RT_1D ; B = GND
R3477  Q_RES  33.2 1% CHIP  pkg 0402LF  page 81 : A = GPU_NVS_PWR_BRAKE_N ; B = GPU_NVS_PWR_BRAKE_R_N

(kicad_pcb
	(version 20260206)
	(generator "pcbnew")
	(generator_version "10.0")
	(general
		(thickness 1.6)
		(legacy_teardrops no)
	)
	(paper "A4")
	(title_block
		(title "04192023_DAF0TMB3IC0_F0TG_MB_C_brd_V02_OCP.brd")
		(comment 1 "Grand Teton / footprints 569-570 of 8354")
	)
	(layers
		(0 "F.Cu" signal "TOP")
		(4 "In1.Cu" signal "GND")
		(6 "In2.Cu" signal "IN1")
		(8 "In3.Cu" signal "GND1")
		(10 "In4.Cu" signal "IN2")
		(12 "In5.Cu" signal "GND2")
		(14 "In6.Cu" signal "IN3")
		(16 "In7.Cu" signal "GND3")
		(18 "In8.Cu" signal "VCC")
		(20 "In9.Cu" signal "VCC1")
		(22 "In10.Cu" signal "GND4")
		(24 "In11.Cu" signal "IN4")
		(26 "In12.Cu" signal "GND5")
		(28 "In13.Cu" signal "IN5")
		(30 "In14.Cu" signal "GND6")
		(32 "In15.Cu" signal "IN6")
		(34 "In16.Cu" signal "GND7")
		(2 "B.Cu" signal "BOTTOM")
		(9 "F.Adhes" user "F.Adhesive")
		(11 "B.Adhes" user "B.Adhesive")
		(13 "F.Paste" user "Package Geometry/Pastemask Top")
		(15 "B.Paste" user "Package Geometry/Pastemask Bottom")
		(5 "F.SilkS" user "Ref Des/Silkscreen Top")
		(7 "B.SilkS" user "Ref Des/Silkscreen Bottom")
		(1 "F.Mask" user "Board Geometry/Soldermask Top")
		(3 "B.Mask" user "Board Geometry/Soldermask Bottom")
		(17 "Dwgs.User" user "User.Drawings")
		(19 "Cmts.User" user "User.Comments")
		(21 "Eco1.User" user "User.Eco1")
		(23 "Eco2.User" user "User.Eco2")
		(25 "Edge.Cuts" user "Board Geometry/Outline")
		(27 "Margin" user)
		(31 "F.CrtYd" user "Package Geometry/Place Bound Top")
		(29 "B.CrtYd" user "Package Geometry/Place Bound Bottom")
		(35 "F.Fab" user "Ref Des/Assembly Top")
		(33 "B.Fab" user "Ref Des/Assembly Bottom")
	)
	(footprint ""
		(layer "F.Cu")
		(at 174.78248 -385.578604 90)
		(property "Reference" "C368"
			(at 0 0 90)
			(layer "F.SilkS")
			(hide yes)
			(effects
				(font
					(size 1.27 1.27)
				)
			)
		)
		(property "Value" ""
			(at 0 0 90)
			(layer "F.Fab")
			(effects
				(font
					(size 1.27 1.27)
				)
			)
		)
		(duplicate_pad_numbers_are_jumpers no)
		(fp_line
			(start 0.7874 -0.4064)
			(end 0.7874 0.4064)
			(stroke
				(width 0.1524)
				(type default)
			)
			(layer "F.SilkS")
		)
		(fp_line
			(start -0.7874 -0.4064)
			(end 0.7874 -0.4064)
			(stroke
				(width 0.1524)
				(type default)
			)
			(layer "F.SilkS")
		)
		(fp_line
			(start 0.7874 0.4064)
			(end -0.7874 0.4064)
			(stroke
				(width 0.1524)
				(type default)
			)
			(layer "F.SilkS")
		)
		(fp_line
			(start -0.7874 0.4064)
			(end -0.7874 -0.4064)
			(stroke
				(width 0.1524)
				(type default)
			)
			(layer "F.SilkS")
		)
		(fp_line
			(start -0.12065 -0.305054)
			(end -0.12065 -0.2794)
			(stroke
				(width 0.1)
				(type default)
			)
			(layer "F.Fab")
		)
		(fp_line
			(start -0.67945 -0.305054)
			(end -0.12065 -0.305054)
			(stroke
				(width 0.1)
				(type default)
			)
			(layer "F.Fab")
		)
		(fp_line
			(start 0.67945 -0.3048)
			(end 0.67945 0.3048)
			(stroke
				(width 0.1)
				(type default)
			)
			(layer "F.Fab")
		)
		(fp_line
			(start 0.12065 -0.3048)
			(end 0.67945 -0.3048)
			(stroke
				(width 0.1)
				(type default)
			)
			(layer "F.Fab")
		)
		(fp_line
			(start 0.12065 -0.2794)
			(end 0.12065 -0.3048)
			(stroke
				(width 0.1)
				(type default)
			)
			(layer "F.Fab")
		)
		(fp_line
			(start -0.12065 -0.2794)
			(end 0.12065 -0.2794)
			(stroke
				(width 0.1)
				(type default)
			)
			(layer "F.Fab")
		)
		(fp_line
			(start 0.120396 0.2794)
			(end -0.12065 0.2794)
			(stroke
				(width 0.1)
				(type default)
			)
			(layer "F.Fab")
		)
		(fp_line
			(start -0.12065 0.2794)
			(end -0.12065 0.3048)
			(stroke
				(width 0.1)
				(type default)
			)
			(layer "F.Fab")
		)
		(fp_line
			(start 0.67945 0.3048)
			(end 0.120396 0.3048)
			(stroke
				(width 0.1)
				(type default)
			)
			(layer "F.Fab")
		)
		(fp_line
			(start 0.120396 0.3048)
			(end 0.120396 0.2794)
			(stroke
				(width 0.1)
				(type default)
			)
			(layer "F.Fab")
		)
		(fp_line
			(start -0.12065 0.3048)
			(end -0.67945 0.3048)
			(stroke
				(width 0.1)
				(type default)
			)
			(layer "F.Fab")
		)
		(fp_line
			(start -0.67945 0.3048)
			(end -0.67945 -0.305054)
			(stroke
				(width 0.1)
				(type default)
			)
			(layer "F.Fab")
		)
		(pad "1" smd circle
			(at -0.40005 0 90)
			(size 0 0)
			(layers "F.Cu" "F.Mask" "F.Paste")
			(net "P1V8_CPU1_RT_1D")
		)
		(pad "2" smd circle
			(at 0.40005 0 90)
			(size 0 0)
			(layers "F.Cu" "F.Mask" "F.Paste")
			(net "GND")
		)
	)
	(footprint ""
		(layer "F.Cu")
		(at 196.977 -100.294948 90)
		(property "Reference" "R3477"
			(at 0 0 90)
			(layer "F.SilkS")
			(hide yes)
			(effects
				(font
					(size 1.27 1.27)
				)
			)
		)
		(property "Value" ""
			(at 0 0 90)
			(layer "F.Fab")
			(effects
				(font
					(size 1.27 1.27)
				)
			)
		)
		(duplicate_pad_numbers_are_jumpers no)
		(fp_line
			(start 0.7874 -0.4064)
			(end 0.7874 0.4064)
			(stroke
				(width 0.1524)
				(type default)
			)
			(layer "F.SilkS")
		)
		(fp_line
			(start -0.7874 -0.4064)
			(end 0.7874 -0.4064)
			(stroke
				(width 0.1524)
				(type default)
			)
			(layer "F.SilkS")
		)
		(fp_line
			(start 0.7874 0.4064)
			(end -0.7874 0.4064)
			(stroke
				(width 0.1524)
				(type default)
			)
			(layer "F.SilkS")
		)
		(fp_line
			(start -0.7874 0.4064)
			(end -0.7874 -0.4064)
			(stroke
				(width 0.1524)
				(type default)
			)
			(layer "F.SilkS")
		)
		(fp_line
			(start -0.12065 -0.305054)
			(end -0.12065 -0.2794)
			(stroke
				(width 0.1)
				(type default)
			)
			(layer "F.Fab")
		)
		(fp_line
			(start -0.67945 -0.305054)
			(end -0.12065 -0.305054)
			(stroke
				(width 0.1)
				(type default)
			)
			(layer "F.Fab")
		)
		(fp_line
			(start 0.67945 -0.3048)
			(end 0.67945 0.3048)
			(stroke
				(width 0.1)
				(type default)
			)
			(layer "F.Fab")
		)
		(fp_line
			(start 0.12065 -0.3048)
			(end 0.67945 -0.3048)
			(stroke
				(width 0.1)
				(type default)
			)
			(layer "F.Fab")
		)
		(fp_line
			(start 0.12065 -0.2794)
			(end 0.12065 -0.3048)
			(stroke
				(width 0.1)
				(type default)
			)
			(layer "F.Fab")
		)
		(fp_line
			(start -0.12065 -0.2794)
			(end 0.12065 -0.2794)
			(stroke
				(width 0.1)
				(type default)
			)
			(layer "F.Fab")
		)
		(fp_line
			(start 0.120396 0.2794)
			(end -0.12065 0.2794)
			(stroke
				(width 0.1)
				(type default)
			)
			(layer "F.Fab")
		)
		(fp_line
			(start -0.12065 0.2794)
			(end -0.12065 0.3048)
			(stroke
				(width 0.1)
				(type default)
			)
			(layer "F.Fab")
		)
		(fp_line
			(start 0.67945 0.3048)
			(end 0.120396 0.3048)
			(stroke
				(width 0.1)
				(type default)
			)
			(layer "F.Fab")
		)
		(fp_line
			(start 0.120396 0.3048)
			(end 0.120396 0.2794)
			(stroke
				(width 0.1)
				(type default)
			)
			(layer "F.Fab")
		)
		(fp_line
			(start -0.12065 0.3048)
			(end -0.67945 0.3048)
			(stroke
				(width 0.1)
				(type default)
			)
			(layer "F.Fab")
		)
		(fp_line
			(start -0.67945 0.3048)
			(end -0.67945 -0.305054)
			(stroke
				(width 0.1)
				(type default)
			)
			(layer "F.Fab")
		)
		(pad "1" smd circle
			(at -0.40005 0 90)
			(size 0 0)
			(layers "F.Cu" "F.Mask" "F.Paste")
			(net "GPU_NVS_PWR_BRAKE_N")
		)
		(pad "2" smd circle
			(at 0.40005 0 90)
			(size 0 0)
			(layers "F.Cu" "F.Mask" "F.Paste")
			(net "GPU_NVS_PWR_BRAKE_R_N")
		)
	)
)
